(kicad_pcb
	(version 20241229)
	(generator "pcbnew")
	(generator_version "9.0")
	(general
		(thickness 1.6296)
		(legacy_teardrops no)
	)
	(paper "A3")
	(title_block
		(title "Thunderbolt to 10GbE adapter")
		(date "2026-04-21")
		(rev "1.1.0")
		(company "Antmicro Ltd")
		(comment 1 "www.antmicro.com")
		(comment 9 "footprints 92-95 of 703")
	)
	(layers
		(0 "F.Cu" signal)
		(4 "In1.Cu" signal)
		(6 "In2.Cu" signal)
		(8 "In3.Cu" signal)
		(10 "In4.Cu" signal)
		(12 "In5.Cu" signal)
		(14 "In6.Cu" signal)
		(2 "B.Cu" signal)
		(9 "F.Adhes" user "F.Adhesive")
		(11 "B.Adhes" user "B.Adhesive")
		(13 "F.Paste" user)
		(15 "B.Paste" user)
		(5 "F.SilkS" user "F.Silkscreen")
		(7 "B.SilkS" user "B.Silkscreen")
		(1 "F.Mask" user)
		(3 "B.Mask" user)
		(17 "Dwgs.User" user "User.Drawings")
		(19 "Cmts.User" user "User.Comments")
		(21 "Eco1.User" user "User.Eco1")
		(23 "Eco2.User" user "User.Eco2")
		(25 "Edge.Cuts" user)
		(27 "Margin" user)
		(31 "F.CrtYd" user "F.Courtyard")
		(29 "B.CrtYd" user "B.Courtyard")
		(35 "F.Fab" user)
		(33 "B.Fab" user)
	)
	(footprint "antmicro-footprints:R_0402_1005Metric"
		(layer "F.Cu")
		(at 158.105 69.074999 -90)
		(descr "Resistor SMD 0402")
		(tags "resistor SMD 0402")
		(property "Reference" "R171"
			(at -11.574999 -20.295 270)
			(layer "F.SilkS")
			(effects
				(font
					(size 0.7 0.7)
					(thickness 0.15)
				)
			)
		)
		(property "Value" "R_100R_0402"
			(at -1.011843 1.772047 270)
			(layer "F.Fab")
			(effects
				(font
					(size 0.7 0.7)
					(thickness 0.15)
				)
				(justify left bottom)
			)
		)
		(property "Datasheet" "https://www.bourns.com/docs/product-datasheets/cr.pdf"
			(at 0 0 270)
			(layer "F.Fab")
			(hide yes)
			(effects
				(font
					(size 1.27 1.27)
					(thickness 0.15)
				)
			)
		)
		(property "Description" "SMD Chip Resistor, 100 ohm, ± 1%, 62.5 mW, 0402 [1005 Metric], Thick Film, General Purpose"
			(at 0 0 270)
			(layer "F.Fab")
			(hide yes)
			(effects
				(font
					(size 1.27 1.27)
					(thickness 0.15)
				)
			)
		)
		(property "MPN" "CR0402-FX-1000GLF"
			(at 0 0 270)
			(unlocked yes)
			(layer "F.Fab")
			(hide yes)
			(effects
				(font
					(size 1 1)
					(thickness 0.15)
				)
			)
		)
		(property "Manufacturer" "Bourns"
			(at 0 0 270)
			(unlocked yes)
			(layer "F.Fab")
			(hide yes)
			(effects
				(font
					(size 1 1)
					(thickness 0.15)
				)
			)
		)
		(property "License" "Apache-2.0"
			(at 0 0 270)
			(unlocked yes)
			(layer "F.Fab")
			(hide yes)
			(effects
				(font
					(size 1 1)
					(thickness 0.15)
				)
			)
		)
		(property "Author" "Antmicro"
			(at 0 0 270)
			(unlocked yes)
			(layer "F.Fab")
			(hide yes)
			(effects
				(font
					(size 1 1)
					(thickness 0.15)
				)
			)
		)
		(property "Val" "100R"
			(at 0 0 270)
			(unlocked yes)
			(layer "F.Fab")
			(hide yes)
			(effects
				(font
					(size 1 1)
					(thickness 0.15)
				)
			)
		)
		(property "Tolerance" "1%"
			(at 0 0 270)
			(unlocked yes)
			(layer "F.Fab")
			(hide yes)
			(effects
				(font
					(size 1 1)
					(thickness 0.15)
				)
			)
		)
		(sheetname "/X710-AT2 Misc/")
		(sheetfile "x710-at2-mics.kicad_sch")
		(attr smd dnp)
		(fp_rect
			(start -0.925 -0.47)
			(end 0.925 0.47)
			(stroke
				(width 0.05)
				(type default)
			)
			(fill no)
			(layer "F.CrtYd")
		)
		(fp_rect
			(start -0.5 -0.25)
			(end 0.5 0.25)
			(stroke
				(width 0.15)
				(type solid)
			)
			(fill no)
			(layer "F.Fab")
		)
		(fp_text user "${REFERENCE}"
			(at -0.95 3.168 270)
			(layer "F.Fab")
			(effects
				(font
					(size 0.7 0.7)
					(thickness 0.15)
				)
				(justify left bottom)
			)
		)
		(fp_text user "License: Apache-2.0"
			(at -0.95 5.169 270)
			(layer "F.Fab")
			(effects
				(font
					(size 0.7 0.7)
					(thickness 0.15)
				)
				(justify left bottom)
			)
		)
		(fp_text user "Author: Antmicro"
			(at -0.95 4.169 270)
			(layer "F.Fab")
			(effects
				(font
					(size 0.7 0.7)
					(thickness 0.15)
				)
				(justify left bottom)
			)
		)
		(pad "1" smd roundrect
			(at -0.48 0 270)
			(size 0.59 0.64)
			(layers "F.Cu" "F.Mask" "F.Paste")
			(roundrect_rratio 0.25)
			(net 23 "GND")
			(pintype "passive")
		)
		(pad "2" smd roundrect
			(at 0.48 0 270)
			(size 0.59 0.64)
			(layers "F.Cu" "F.Mask" "F.Paste")
			(roundrect_rratio 0.25)
			(net 127 "/X710-AT2 Misc/~{DEV_DIS}")
			(pintype "passive")
		)
	)
	(footprint "antmicro-footprints:C_0805_2012Metric"
		(layer "F.Cu")
		(at 165.305 97.024999 180)
		(descr "Capacitor SMD 0805")
		(tags "capacitor SMD 0805")
		(property "Reference" "C179"
			(at -7.695 0 180)
			(layer "F.SilkS")
			(effects
				(font
					(size 0.7 0.7)
					(thickness 0.15)
				)
			)
		)
		(property "Value" "C_100u_0805"
			(at -2.055717 1.963152 180)
			(layer "F.Fab")
			(effects
				(font
					(size 0.7 0.7)
					(thickness 0.15)
				)
				(justify left bottom)
			)
		)
		(property "Datasheet" "https://www.murata.com/products/productdetail?partno=GRM21BR60J107ME15%23"
			(at 0 0 180)
			(layer "F.Fab")
			(hide yes)
			(effects
				(font
					(size 1.27 1.27)
					(thickness 0.15)
				)
			)
		)
		(property "Description" "SMD Multilayer Ceramic Capacitor, 100 µF, 6.3 V, 0805 [2012 Metric], ± 20%, X5R, GRM Series"
			(at 0 0 180)
			(layer "F.Fab")
			(hide yes)
			(effects
				(font
					(size 1.27 1.27)
					(thickness 0.15)
				)
			)
		)
		(property "MPN" "GRM21BR60J107ME15L"
			(at 0 0 180)
			(unlocked yes)
			(layer "F.Fab")
			(hide yes)
			(effects
				(font
					(size 1 1)
					(thickness 0.15)
				)
			)
		)
		(property "Manufacturer" "Murata"
			(at 0 0 180)
			(unlocked yes)
			(layer "F.Fab")
			(hide yes)
			(effects
				(font
					(size 1 1)
					(thickness 0.15)
				)
			)
		)
		(property "License" "Apache-2.0"
			(at 0 0 180)
			(unlocked yes)
			(layer "F.Fab")
			(hide yes)
			(effects
				(font
					(size 1 1)
					(thickness 0.15)
				)
			)
		)
		(property "Author" "Antmicro"
			(at 0 0 180)
			(unlocked yes)
			(layer "F.Fab")
			(hide yes)
			(effects
				(font
					(size 1 1)
					(thickness 0.15)
				)
			)
		)
		(property "Val" "100u"
			(at 0 0 180)
			(unlocked yes)
			(layer "F.Fab")
			(hide yes)
			(effects
				(font
					(size 1 1)
					(thickness 0.15)
				)
			)
		)
		(property "Voltage" ""
			(at 0 0 180)
			(unlocked yes)
			(layer "F.Fab")
			(hide yes)
			(effects
				(font
					(size 1 1)
					(thickness 0.15)
				)
			)
		)
		(property "Dielectric" ""
			(at 0 0 180)
			(unlocked yes)
			(layer "F.Fab")
			(hide yes)
			(effects
				(font
					(size 1 1)
					(thickness 0.15)
				)
			)
		)
		(property "Public" "False"
			(at 0 0 180)
			(unlocked yes)
			(layer "F.Fab")
			(hide yes)
			(effects
				(font
					(size 1 1)
					(thickness 0.15)
				)
			)
		)
		(sheetname "/X710-AT2 power/")
		(sheetfile "x710-at2-power.kicad_sch")
		(attr smd)
		(fp_line
			(start -0.3 0.7)
			(end 0.3 0.7)
			(stroke
				(width 0.15)
				(type solid)
			)
			(layer "F.SilkS")
		)
		(fp_line
			(start -0.3 -0.7)
			(end 0.3 -0.7)
			(stroke
				(width 0.15)
				(type solid)
			)
			(layer "F.SilkS")
		)
		(fp_rect
			(start 1.95 -0.9)
			(end -1.95 0.9)
			(stroke
				(width 0.05)
				(type default)
			)
			(fill no)
			(layer "F.CrtYd")
		)
		(fp_rect
			(start -0.95 -0.675)
			(end 0.95 0.675)
			(stroke
				(width 0.15)
				(type solid)
			)
			(fill no)
			(layer "F.Fab")
		)
		(fp_text user "${REFERENCE}"
			(at -1.9 3.947 180)
			(layer "F.Fab")
			(effects
				(font
					(size 0.7 0.7)
					(thickness 0.15)
				)
				(justify left bottom)
			)
		)
		(fp_text user "License: Apache-2.0"
			(at -1.9 4.947 180)
			(layer "F.Fab")
			(effects
				(font
					(size 0.7 0.7)
					(thickness 0.15)
				)
				(justify left bottom)
			)
		)
		(fp_text user "Author: Antmicro"
			(at -1.9 5.947 180)
			(layer "F.Fab")
			(effects
				(font
					(size 0.7 0.7)
					(thickness 0.15)
				)
				(justify left bottom)
			)
		)
		(pad "1" smd roundrect
			(at -1.1 0 180)
			(size 1.2 1.3)
			(layers "F.Cu" "F.Mask" "F.Paste")
			(roundrect_rratio 0.25)
			(net 23 "GND")
			(pintype "passive")
		)
		(pad "2" smd roundrect
			(at 1.1 0 180)
			(size 1.2 1.3)
			(layers "F.Cu" "F.Mask" "F.Paste")
			(roundrect_rratio 0.25)
			(net 14 "P1_AVDDL")
			(pintype "passive")
		)
	)
	(footprint "antmicro-footprints:VQFN-HR-9_2x1.5mm"
		(layer "F.Cu")
		(at 162.15 110.15)
		(property "Reference" "U12"
			(at 12.450003 17.049998 0)
			(layer "F.SilkS")
			(effects
				(font
					(size 0.7 0.7)
					(thickness 0.15)
				)
			)
		)
		(property "Value" "TPS566231P"
			(at -1.65 2.15 0)
			(layer "F.Fab")
			(effects
				(font
					(size 0.7 0.7)
					(thickness 0.15)
				)
				(justify left bottom)
			)
		)
		(property "Datasheet" "https://www.ti.com/lit/ds/symlink/tps566231.pdf"
			(at 0 -0.045 0)
			(layer "F.Fab")
			(effects
				(font
					(size 0.7 0.7)
					(thickness 0.15)
				)
				(justify left bottom)
			)
		)
		(property "Description" "Switching Voltage Regulators 3-V to 18-V, 6-A synchronous buck converter"
			(at -1.45 3.65 0)
			(layer "F.Fab")
			(effects
				(font
					(size 0.7 0.7)
					(thickness 0.15)
				)
				(justify left bottom)
			)
		)
		(property "Manufacturer" "Texas Instruments"
			(at 0 0 0)
			(unlocked yes)
			(layer "F.Fab")
			(hide yes)
			(effects
				(font
					(size 1 1)
					(thickness 0.15)
				)
			)
		)
		(property "MPN" "TPS566231PRQFR"
			(at 0 0 0)
			(unlocked yes)
			(layer "F.Fab")
			(hide yes)
			(effects
				(font
					(size 1 1)
					(thickness 0.15)
				)
			)
		)
		(property "Author" "Antmicro"
			(at 0 0 0)
			(unlocked yes)
			(layer "F.Fab")
			(hide yes)
			(effects
				(font
					(size 1 1)
					(thickness 0.15)
				)
			)
		)
		(property "License" "Apache-2.0"
			(at 0 0 0)
			(unlocked yes)
			(layer "F.Fab")
			(hide yes)
			(effects
				(font
					(size 1 1)
					(thickness 0.15)
				)
			)
		)
		(sheetname "/X710 DCDC converters/")
		(sheetfile "DCDC_converters_X710.kicad_sch")
		(attr smd)
		(fp_line
			(start -1 -0.945)
			(end -0.695 -0.945)
			(stroke
				(width 0.15)
				(type solid)
			)
			(layer "F.SilkS")
		)
		(fp_line
			(start -1 0.945)
			(end -0.695 0.945)
			(stroke
				(width 0.15)
				(type solid)
			)
			(layer "F.SilkS")
		)
		(fp_line
			(start 1 -0.945)
			(end 0.695 -0.945)
			(stroke
				(width 0.15)
				(type solid)
			)
			(layer "F.SilkS")
		)
		(fp_line
			(start 1 0.945)
			(end 0.2 0.945)
			(stroke
				(width 0.15)
				(type solid)
			)
			(layer "F.SilkS")
		)
		(fp_circle
			(center -1.18 -0.77)
			(end -1.13 -0.77)
			(stroke
				(width 0.15)
				(type solid)
			)
			(fill yes)
			(layer "F.SilkS")
		)
		(fp_rect
			(start -1.3 -1.05)
			(end 1.3 1.05)
			(stroke
				(width 0.05)
				(type solid)
			)
			(fill no)
			(layer "F.CrtYd")
		)
		(fp_rect
			(start -1 -0.75)
			(end 1 0.75)
			(stroke
				(width 0.15)
				(type solid)
			)
			(fill no)
			(layer "F.Fab")
		)
		(fp_text user "Author: Antmicro"
			(at -1.65 4.55 0)
			(layer "F.Fab")
			(effects
				(font
					(size 0.7 0.7)
					(thickness 0.15)
				)
				(justify left bottom)
			)
		)
		(fp_text user "${REFERENCE}"
			(at -1.65 3.35 0)
			(layer "F.Fab")
			(effects
				(font
					(size 0.7 0.7)
					(thickness 0.15)
				)
				(justify left bottom)
			)
		)
		(fp_text user "License: Apache-2.0"
			(at -1.65 5.75 0)
			(layer "F.Fab")
			(effects
				(font
					(size 0.7 0.7)
					(thickness 0.15)
				)
				(justify left bottom)
			)
		)
		(pad "1" smd roundrect
			(at -0.925 -0.5)
			(size 0.55 0.25)
			(layers "F.Cu" "F.Mask" "F.Paste")
			(roundrect_rratio 0.125)
			(net 109 "/X710 DCDC converters/1V0_VCC")
			(pinfunction "V_{CC}")
			(pintype "passive")
		)
		(pad "2" smd roundrect
			(at -0.925 0)
			(size 0.55 0.25)
			(layers "F.Cu" "F.Mask" "F.Paste")
			(roundrect_rratio 0.125)
			(net 340 "/X710 DCDC converters/1V0_FB")
			(pinfunction "FB")
			(pintype "input")
		)
		(pad "3" smd roundrect
			(at -0.925 0.5)
			(size 0.55 0.25)
			(layers "F.Cu" "F.Mask" "F.Paste")
			(roundrect_rratio 0.125)
			(net 385 "/X710 DCDC converters/1V0_EN")
			(pinfunction "EN")
			(pintype "input")
		)
		(pad "4" smd roundrect
			(at -0.25 0.45)
			(size 0.25 1)
			(layers "F.Cu" "F.Mask" "F.Paste")
			(roundrect_rratio 0.125)
			(net 23 "GND")
			(pinfunction "PGND")
			(pintype "power_in")
		)
		(pad "5" smd roundrect
			(at 0.925 0.5)
			(size 0.55 0.25)
			(layers "F.Cu" "F.Mask" "F.Paste")
			(roundrect_rratio 0.125)
			(net 40 "+5V")
			(pinfunction "V_{IN}")
			(pintype "power_in")
		)
		(pad "6" smd roundrect
			(at 0.925 0)
			(size 0.55 0.25)
			(layers "F.Cu" "F.Mask" "F.Paste")
			(roundrect_rratio 0.125)
			(net 40 "+5V")
			(pinfunction "V_{IN}")
			(pintype "passive")
		)
		(pad "7" smd roundrect
			(at 0.925 -0.5)
			(size 0.55 0.25)
			(layers "F.Cu" "F.Mask" "F.Paste")
			(roundrect_rratio 0.125)
			(net 307 "/X710 DCDC converters/1V0_BST")
			(pinfunction "BST")
			(pintype "passive")
		)
		(pad "8" smd roundrect
			(at 0.25 -0.3)
			(size 0.25 1.3)
			(layers "F.Cu" "F.Mask" "F.Paste")
			(roundrect_rratio 0.125)
			(net 310 "/X710 DCDC converters/1V0_SW")
			(pinfunction "SW")
			(pintype "power_out")
		)
		(pad "9" smd roundrect
			(at -0.25 -0.675)
			(size 0.25 0.55)
			(layers "F.Cu" "F.Mask" "F.Paste")
			(roundrect_rratio 0.125)
			(net 381 "/X710 DCDC converters/1V0_PG")
			(pinfunction "PG")
			(pintype "passive")
		)
	)
	(footprint "antmicro-footprints:C_0402_1005Metric"
		(layer "F.Cu")
		(at 121.948107 88.554085 90)
		(descr "Capacitor SMD 0402")
		(tags "capacitor SMD 0402")
		(property "Reference" "C63"
			(at -3.245915 0.451893 90)
			(layer "F.SilkS")
			(effects
				(font
					(size 0.7 0.7)
					(thickness 0.15)
				)
				(justify left bottom)
			)
		)
		(property "Value" "C_100n_0402"
			(at -1.022927 2.155213 90)
			(layer "F.Fab")
			(effects
				(font
					(size 0.7 0.7)
					(thickness 0.15)
				)
				(justify left bottom)
			)
		)
		(property "Datasheet" "https://www.murata.com/products/productdetail?partno=GRM155R61H104KE14%23"
			(at 0 0 90)
			(layer "F.Fab")
			(hide yes)
			(effects
				(font
					(size 1.27 1.27)
					(thickness 0.15)
				)
			)
		)
		(property "Description" "SMD Multilayer Ceramic Capacitor, 0.1 µF, 50 V, 0402 [1005 Metric], ± 10%, X5R, GRM Series"
			(at 0 0 90)
			(layer "F.Fab")
			(hide yes)
			(effects
				(font
					(size 1.27 1.27)
					(thickness 0.15)
				)
			)
		)
		(property "MPN" "GRM155R61H104KE14D"
			(at 0 0 90)
			(unlocked yes)
			(layer "F.Fab")
			(hide yes)
			(effects
				(font
					(size 1 1)
					(thickness 0.15)
				)
			)
		)
		(property "Manufacturer" "Murata"
			(at 0 0 90)
			(unlocked yes)
			(layer "F.Fab")
			(hide yes)
			(effects
				(font
					(size 1 1)
					(thickness 0.15)
				)
			)
		)
		(property "License" "Apache-2.0"
			(at 0 0 90)
			(unlocked yes)
			(layer "F.Fab")
			(hide yes)
			(effects
				(font
					(size 1 1)
					(thickness 0.15)
				)
			)
		)
		(property "Val" "100n"
			(at 0 0 90)
			(unlocked yes)
			(layer "F.Fab")
			(hide yes)
			(effects
				(font
					(size 1 1)
					(thickness 0.15)
				)
			)
		)
		(property "Voltage" "50V"
			(at 0 0 90)
			(unlocked yes)
			(layer "F.Fab")
			(hide yes)
			(effects
				(font
					(size 1 1)
					(thickness 0.15)
				)
			)
		)
		(property "Dielectric" "X5R"
			(at 0 0 90)
			(unlocked yes)
			(layer "F.Fab")
			(hide yes)
			(effects
				(font
					(size 1 1)
					(thickness 0.15)
				)
			)
		)
		(property "Author" "Antmicro"
			(at 0 0 90)
			(unlocked yes)
			(layer "F.Fab")
			(hide yes)
			(effects
				(font
					(size 1 1)
					(thickness 0.15)
				)
			)
		)
		(sheetname "/TB Controller - Power/")
		(sheetfile "tb-power.kicad_sch")
		(attr smd)
		(fp_rect
			(start -0.925 -0.47)
			(end 0.925 0.47)
			(stroke
				(width 0.05)
				(type default)
			)
			(fill no)
			(layer "F.CrtYd")
		)
		(fp_line
			(start 0.504 -0.25)
			(end 0.504 0.248)
			(stroke
				(width 0.15)
				(type solid)
			)
			(layer "F.Fab")
		)
		(fp_line
			(start -0.494 -0.25)
			(end 0.504 -0.25)
			(stroke
				(width 0.15)
				(type solid)
			)
			(layer "F.Fab")
		)
		(fp_line
			(start 0.504 0.248)
			(end -0.494 0.248)
			(stroke
				(width 0.15)
				(type solid)
			)
			(layer "F.Fab")
		)
		(fp_line
			(start -0.494 0.248)
			(end -0.494 -0.25)
			(stroke
				(width 0.15)
				(type solid)
			)
			(layer "F.Fab")
		)
		(fp_text user "${REFERENCE}"
			(at -0.939 4.599 90)
			(layer "F.Fab")
			(effects
				(font
					(size 0.7 0.7)
					(thickness 0.15)
				)
				(justify left bottom)
			)
		)
		(fp_text user "Author: Antmicro"
			(at -0.939 3.399 90)
			(layer "F.Fab")
			(effects
				(font
					(size 0.7 0.7)
					(thickness 0.15)
				)
				(justify left bottom)
			)
		)
		(fp_text user "License: Apache-2.0"
			(at -0.939 5.799 90)
			(layer "F.Fab")
			(effects
				(font
					(size 0.7 0.7)
					(thickness 0.15)
				)
				(justify left bottom)
			)
		)
		(pad "1" smd roundrect
			(at -0.48 0 90)
			(size 0.59 0.64)
			(layers "F.Cu" "F.Mask" "F.Paste")
			(roundrect_rratio 0.25)
			(net 23 "GND")
			(pintype "passive")
		)
		(pad "2" smd roundrect
			(at 0.48 0 90)
			(size 0.59 0.64)
			(layers "F.Cu" "F.Mask" "F.Paste")
			(roundrect_rratio 0.25)
			(net 57 "+3V3_TB")
			(pintype "passive")
		)
	)
)
